(kicad_pcb
	(version 20211014)
	(generator pcbnew)
	(general
    (thickness 1.6)
  )
	(paper "A4")
	(title_block
    (title "SA800U (Snapdragon 845) Baseboard")
    (date "2023-10-19")
    (rev "1.0.3")
    (company "Antmicro Ltd.")
    (comment 1 "www.antmicro.com")
		(comment 9 "footprints 225-233 of 589")
	)
	(layers
    (0 "F.Cu" signal)
    (1 "In1.Cu" power)
    (2 "In2.Cu" signal)
    (3 "In3.Cu" signal)
    (4 "In4.Cu" power)
    (31 "B.Cu" signal)
    (32 "B.Adhes" user "B.Adhesive")
    (33 "F.Adhes" user "F.Adhesive")
    (34 "B.Paste" user)
    (35 "F.Paste" user)
    (36 "B.SilkS" user "B.Silkscreen")
    (37 "F.SilkS" user "F.Silkscreen")
    (38 "B.Mask" user)
    (39 "F.Mask" user)
    (40 "Dwgs.User" user "User.Drawings")
    (41 "Cmts.User" user "User.Comments")
    (42 "Eco1.User" user "User.Eco1")
    (43 "Eco2.User" user "User.Eco2")
    (44 "Edge.Cuts" user)
    (45 "Margin" user)
    (46 "B.CrtYd" user "B.Courtyard")
    (47 "F.CrtYd" user "F.Courtyard")
    (48 "B.Fab" user)
    (49 "F.Fab" user)
  )
	(footprint "sa800u-baseboard-hw-footprints:Oscillator_SMD_Geyer_KX-7-4Pin_3.2x2.5mm" (layer "F.Cu")
    (tedit 5D7218CB)
    (at 148.188164 128.312952 -90)
    (property "Author" "Antmicro")
    (property "License" "Apache-2.0")
    (property "MPN" "ABM8G-24.000MHZ-18-D2Y-T")
    (property "Manufacturer" "Abracon")
    (property "Sheetfile" "hdmi-converter.kicad_sch")
    (property "Sheetname" "HDMI converter")
    (property "Val" "24.000MHz")
    (attr smd)
    (fp_text reference "Y2" (at -2.052952 1.828164 180) (layer "F.SilkS")
      (effects (font (size 0.7 0.7) (thickness 0.15)) (justify left bottom))
    )
    (fp_text value "ABM8G-24.000MHZ-18-D2Y-T" (at -1.75 2.548 -90) (layer "F.Fab")
      (effects (font (size 0.7 0.7) (thickness 0.15)) (justify left bottom))
    )
    (fp_text user "License: Apache-2.0" (at -1.75 6.5 -90) (layer "F.Fab") hide
      (effects (font (size 0.7 0.7) (thickness 0.15)) (justify left bottom))
    )
    (fp_text user "${REFERENCE}" (at -1.75 3.75 -90) (layer "F.Fab") hide
      (effects (font (size 0.7 0.7) (thickness 0.15)) (justify left bottom))
    )
    (fp_text user "Author: Antmicro" (at -1.75 5 -90) (layer "F.Fab") hide
      (effects (font (size 0.7 0.7) (thickness 0.15)) (justify left bottom))
    )
    (fp_line (start -0.35 -1.25) (end 0.45 -1.25) (layer "F.SilkS") (width 0.15))
    (fp_line (start -0.35 1.25) (end 0.45 1.25) (layer "F.SilkS") (width 0.15))
    (fp_line (start -1.6 0.3) (end -1.6 -0.2) (layer "F.SilkS") (width 0.15))
    (fp_line (start 1.6 0.3) (end 1.6 -0.2) (layer "F.SilkS") (width 0.15))
    (fp_circle (center -1.75 1.5) (end -1.7 1.5) (layer "F.SilkS") (width 0.15) (fill none))
    (fp_rect (start -1.907 -1.55) (end 2.006 1.649) (layer "F.CrtYd") (width 0.05) (fill none))
    (pad "1" smd roundrect (at -1.101 0.949 270) (size 1.3 1.1) (layers "F.Cu" "F.Paste" "F.Mask") (roundrect_rratio 0)
      (chamfer_ratio 0.2) (chamfer bottom_left)
      (net 190 "/HDMI converter/XTALO") (pintype "passive"))
    (pad "2" smd rect (at 1.199 0.949 270) (size 1.3 1.1) (layers "F.Cu" "F.Paste" "F.Mask")
      (net 1 "GND") (pinfunction "SH") (pintype "passive"))
    (pad "3" smd rect (at 1.199 -0.85 270) (size 1.3 1.1) (layers "F.Cu" "F.Paste" "F.Mask")
      (net 192 "/HDMI converter/XTALI") (pintype "passive"))
    (pad "4" smd rect (at -1.101 -0.85 270) (size 1.3 1.1) (layers "F.Cu" "F.Paste" "F.Mask")
      (net 1 "GND") (pinfunction "SH") (pintype "passive"))
  )
	(footprint "sa800u-baseboard-hw-footprints:Conn_Molex_NanoFit_1053131202" (layer "F.Cu")
    (tedit 6215E733)
    (at 78.25 143 -90)
    (descr "Molex Nano-Fit Power Connectors, 2 Pins per row (http://www.molex.com/pdm_docs/sd/1053131202_sd.pdf)")
    (tags "connector Molex Nano-Fit NanoFit top entry 2.50mm horizontal")
    (property "Author" "Antmicro")
    (property "License" "Apache-2.0")
    (property "MPN" "1053131202")
    (property "Manufacturer" "Molex")
    (property "Sheetfile" "psu.kicad_sch")
    (property "Sheetname" "PSU")
    (attr through_hole)
    (fp_text reference "J10" (at 1.3 3.83 -90) (layer "F.SilkS")
      (effects (font (size 0.7 0.7) (thickness 0.15)) (justify left bottom))
    )
    (fp_text value "Conn_Molex_NanoFit_1053131202" (at -3.1 5.4 -90) (layer "F.Fab")
      (effects (font (size 0.7 0.7) (thickness 0.15)) (justify left bottom))
    )
    (fp_text user "${REFERENCE}" (at -3.1 7.4 -90) (layer "F.Fab") hide
      (effects (font (size 0.7 0.7) (thickness 0.15)) (justify left bottom))
    )
    (fp_text user "License: Apache-2.0" (at -3.1 8.6 -90) (layer "F.Fab") hide
      (effects (font (size 0.7 0.7) (thickness 0.15)) (justify left bottom))
    )
    (fp_text user "Author: Antmicro" (at -3.1 9.8 -90) (layer "F.Fab") hide
      (effects (font (size 0.7 0.7) (thickness 0.15)) (justify left bottom))
    )
    (fp_rect (start 1.4 -0.299) (end 1.899 0.299) (layer "F.SilkS") (width 0.15) (fill none))
    (fp_rect (start 1.4 2.2) (end 1.899 2.798) (layer "F.SilkS") (width 0.15) (fill none))
    (fp_rect (start 10.4 -1.7) (end 1.898 4.2) (layer "F.SilkS") (width 0.15) (fill none))
    (fp_circle (center 0 -1.25) (end 0.05 -1.25) (layer "F.SilkS") (width 0.15) (fill solid))
    (fp_rect (start -1.097 -2.216) (end 12.342 4.724) (layer "F.CrtYd") (width 0.05) (fill none))
    (fp_line (start -0.35 -1.71) (end -0.595 -1.465) (layer "F.Fab") (width 0.15))
    (fp_rect (start -0.597 -1.716) (end 11.842 4.224) (layer "F.Fab") (width 0.15) (fill none))
    (pad "" np_thru_hole circle (at 7.179 0 270) (size 1.7 1.7) (drill 1.7) (layers *.Cu *.Mask))
    (pad "" np_thru_hole circle (at 7.179 2.499 270) (size 1.7 1.7) (drill 1.7) (layers *.Cu *.Mask))
    (pad "1" thru_hole custom (at 0 0 270) (size 1.417157 1.417157) (drill 1.2) (layers *.Cu *.Mask)
      (net 152 "/PSU/AUX_VDD") (pintype "input")
      (options (clearance outline) (anchor circle))
      (primitives
        (gr_poly (pts
            (xy -0.85 -0.6)
            (xy 0.85 -0.6)
            (xy 0.85 0.6)
            (xy -0.45 0.6)
            (xy -0.85 0.2)
          ) (width 0.5) (fill yes))
      ))
    (pad "2" thru_hole oval (at 0 2.499 270) (size 2.2 1.7) (drill 1.2) (layers *.Cu *.Mask)
      (net 1 "GND") (pintype "input"))
  )
	(footprint "sa800u-baseboard-hw-footprints:R_0402_1005Metric" (layer "F.Cu")
    (tedit 5FD9C158)
    (at 134.388164 125.512952)
    (descr "Resistor SMD 0402")
    (tags "resistor SMD 0402")
    (property "Author" "Antmicro")
    (property "DNP" "DNP")
    (property "License" "Apache-2.0")
    (property "MPN" "CR0402-FX-1001GLF")
    (property "Manufacturer" "Bourns")
    (property "Sheetfile" "hdmi-converter.kicad_sch")
    (property "Sheetname" "HDMI converter")
    (property "Tolerance" "1%")
    (property "Val" "1k")
    (attr exclude_from_pos_files)
    (fp_text reference "R15" (at -4.056328 0.324096) (layer "F.SilkS")
      (effects (font (size 0.7 0.7) (thickness 0.15)) (justify left bottom))
    )
    (fp_text value "R_1k_0402" (at 0 1.4) (layer "F.Fab")
      (effects (font (size 0.7 0.7) (thickness 0.15)) (justify left bottom))
    )
    (fp_text user "Author: Antmicro" (at -0.95 4.169) (layer "F.Fab") hide
      (effects (font (size 0.7 0.7) (thickness 0.15)) (justify left bottom))
    )
    (fp_text user "License: Apache-2.0" (at -0.95 5.169) (layer "F.Fab") hide
      (effects (font (size 0.7 0.7) (thickness 0.15)) (justify left bottom))
    )
    (fp_text user "${REFERENCE}" (at -0.95 3.168) (layer "F.Fab") hide
      (effects (font (size 0.7 0.7) (thickness 0.15)) (justify left bottom))
    )
    (fp_rect (start -0.93 -0.47) (end 0.93 0.47) (layer "F.CrtYd") (width 0.05) (fill none))
    (fp_rect (start -0.5 -0.25) (end 0.5 0.25) (layer "F.Fab") (width 0.15) (fill none))
    (pad "1" smd roundrect (at -0.485 0) (size 0.59 0.64) (layers "F.Cu" "F.Paste" "F.Mask") (roundrect_rratio 0.25)
      (net 131 "3V3_SYS") (pintype "passive"))
    (pad "2" smd roundrect (at 0.485 0) (size 0.59 0.64) (layers "F.Cu" "F.Paste" "F.Mask") (roundrect_rratio 0.25)
      (net 289 "/HDMI converter/I2C_ADDR") (pintype "passive"))
  )
	(footprint "sa800u-baseboard-hw-footprints:R_0402_1005Metric" (layer "F.Cu")
    (tedit 5FD9C158)
    (at 134.388164 121.491425)
    (descr "Resistor SMD 0402")
    (tags "resistor SMD 0402")
    (property "Author" "Antmicro")
    (property "License" "Apache-2.0")
    (property "MPN" "CR0402-FX-4701GLF")
    (property "Manufacturer" "Bourns")
    (property "Sheetfile" "hdmi-converter.kicad_sch")
    (property "Sheetname" "HDMI converter")
    (property "Tolerance" "1%")
    (property "Val" "4k7")
    (attr smd)
    (fp_text reference "R19" (at -3.028164 0.388575) (layer "F.SilkS")
      (effects (font (size 0.7 0.7) (thickness 0.15)) (justify left bottom))
    )
    (fp_text value "R_4k7_0402" (at 0 1.4) (layer "F.Fab")
      (effects (font (size 0.7 0.7) (thickness 0.15)) (justify left bottom))
    )
    (fp_text user "${REFERENCE}" (at -0.95 3.168) (layer "F.Fab") hide
      (effects (font (size 0.7 0.7) (thickness 0.15)) (justify left bottom))
    )
    (fp_text user "License: Apache-2.0" (at -0.95 5.169) (layer "F.Fab") hide
      (effects (font (size 0.7 0.7) (thickness 0.15)) (justify left bottom))
    )
    (fp_text user "Author: Antmicro" (at -0.95 4.169) (layer "F.Fab") hide
      (effects (font (size 0.7 0.7) (thickness 0.15)) (justify left bottom))
    )
    (fp_rect (start -0.93 -0.47) (end 0.93 0.47) (layer "F.CrtYd") (width 0.05) (fill none))
    (fp_rect (start -0.5 -0.25) (end 0.5 0.25) (layer "F.Fab") (width 0.15) (fill none))
    (pad "1" smd roundrect (at -0.485 0) (size 0.59 0.64) (layers "F.Cu" "F.Paste" "F.Mask") (roundrect_rratio 0.25)
      (net 131 "3V3_SYS") (pintype "passive"))
    (pad "2" smd roundrect (at 0.485 0) (size 0.59 0.64) (layers "F.Cu" "F.Paste" "F.Mask") (roundrect_rratio 0.25)
      (net 287 "/HDMI converter/LT9611_SCL") (pintype "passive"))
  )
	(footprint "sa800u-baseboard-hw-footprints:R_0402_1005Metric" (layer "F.Cu")
    (tedit 5FD9C158)
    (at 134.388164 122.491424)
    (descr "Resistor SMD 0402")
    (tags "resistor SMD 0402")
    (property "Author" "Antmicro")
    (property "License" "Apache-2.0")
    (property "MPN" "CR0402-FX-4701GLF")
    (property "Manufacturer" "Bourns")
    (property "Sheetfile" "hdmi-converter.kicad_sch")
    (property "Sheetname" "HDMI converter")
    (property "Tolerance" "1%")
    (property "Val" "4k7")
    (attr smd)
    (fp_text reference "R18" (at -3.028164 0.388575) (layer "F.SilkS")
      (effects (font (size 0.7 0.7) (thickness 0.15)) (justify left bottom))
    )
    (fp_text value "R_4k7_0402" (at 0 1.4) (layer "F.Fab")
      (effects (font (size 0.7 0.7) (thickness 0.15)) (justify left bottom))
    )
    (fp_text user "${REFERENCE}" (at -0.95 3.168) (layer "F.Fab") hide
      (effects (font (size 0.7 0.7) (thickness 0.15)) (justify left bottom))
    )
    (fp_text user "License: Apache-2.0" (at -0.95 5.169) (layer "F.Fab") hide
      (effects (font (size 0.7 0.7) (thickness 0.15)) (justify left bottom))
    )
    (fp_text user "Author: Antmicro" (at -0.95 4.169) (layer "F.Fab") hide
      (effects (font (size 0.7 0.7) (thickness 0.15)) (justify left bottom))
    )
    (fp_rect (start -0.93 -0.47) (end 0.93 0.47) (layer "F.CrtYd") (width 0.05) (fill none))
    (fp_rect (start -0.5 -0.25) (end 0.5 0.25) (layer "F.Fab") (width 0.15) (fill none))
    (pad "1" smd roundrect (at -0.485 0) (size 0.59 0.64) (layers "F.Cu" "F.Paste" "F.Mask") (roundrect_rratio 0.25)
      (net 131 "3V3_SYS") (pintype "passive"))
    (pad "2" smd roundrect (at 0.485 0) (size 0.59 0.64) (layers "F.Cu" "F.Paste" "F.Mask") (roundrect_rratio 0.25)
      (net 288 "/HDMI converter/LT9611_SDA") (pintype "passive"))
  )
	(footprint "sa800u-baseboard-hw-footprints:R_0402_1005Metric" (layer "F.Cu")
    (tedit 5FD9C158)
    (at 134.388164 123.491425)
    (descr "Resistor SMD 0402")
    (tags "resistor SMD 0402")
    (property "Author" "Antmicro")
    (property "License" "Apache-2.0")
    (property "MPN" "CR0402-FX-4701GLF")
    (property "Manufacturer" "Bourns")
    (property "Sheetfile" "hdmi-converter.kicad_sch")
    (property "Sheetname" "HDMI converter")
    (property "Tolerance" "1%")
    (property "Val" "4k7")
    (attr smd)
    (fp_text reference "R20" (at -3.028164 0.388575) (layer "F.SilkS")
      (effects (font (size 0.7 0.7) (thickness 0.15)) (justify left bottom))
    )
    (fp_text value "R_4k7_0402" (at 0 1.4) (layer "F.Fab")
      (effects (font (size 0.7 0.7) (thickness 0.15)) (justify left bottom))
    )
    (fp_text user "Author: Antmicro" (at -0.95 4.169) (layer "F.Fab") hide
      (effects (font (size 0.7 0.7) (thickness 0.15)) (justify left bottom))
    )
    (fp_text user "${REFERENCE}" (at -0.95 3.168) (layer "F.Fab") hide
      (effects (font (size 0.7 0.7) (thickness 0.15)) (justify left bottom))
    )
    (fp_text user "License: Apache-2.0" (at -0.95 5.169) (layer "F.Fab") hide
      (effects (font (size 0.7 0.7) (thickness 0.15)) (justify left bottom))
    )
    (fp_rect (start -0.93 -0.47) (end 0.93 0.47) (layer "F.CrtYd") (width 0.05) (fill none))
    (fp_rect (start -0.5 -0.25) (end 0.5 0.25) (layer "F.Fab") (width 0.15) (fill none))
    (pad "1" smd roundrect (at -0.485 0) (size 0.59 0.64) (layers "F.Cu" "F.Paste" "F.Mask") (roundrect_rratio 0.25)
      (net 131 "3V3_SYS") (pintype "passive"))
    (pad "2" smd roundrect (at 0.485 0) (size 0.59 0.64) (layers "F.Cu" "F.Paste" "F.Mask") (roundrect_rratio 0.25)
      (net 284 "/HDMI converter/LT9611_INTO_GPIO5") (pintype "passive"))
  )
	(footprint "sa800u-baseboard-hw-footprints:C_0402_1005Metric" (layer "F.Cu")
    (tedit 616D63CF)
    (at 134.4 120.5 180)
    (descr "Capacitor SMD 0402")
    (tags "capacitor SMD 0402")
    (property "Author" "Antmicro")
    (property "Dielectric" "")
    (property "License" "Apache-2.0")
    (property "MPN" "C1005X6S1A105K050BC")
    (property "Manufacturer" "TDK")
    (property "Sheetfile" "hdmi-converter.kicad_sch")
    (property "Sheetname" "HDMI converter")
    (property "Val" "1u")
    (property "Voltage" "")
    (attr smd)
    (fp_text reference "C34" (at 3.07 -0.42 180) (layer "F.SilkS")
      (effects (font (size 0.7 0.7) (thickness 0.15)) (justify left bottom))
    )
    (fp_text value "C_1u_0402" (at 0 1.4 180) (layer "F.Fab")
      (effects (font (size 0.7 0.7) (thickness 0.15)) (justify left bottom))
    )
    (fp_text user "Author: Antmicro" (at -0.932 4.17 180) (layer "F.Fab") hide
      (effects (font (size 0.7 0.7) (thickness 0.15)) (justify left bottom))
    )
    (fp_text user "License: Apache-2.0" (at -0.932 5.17 180) (layer "F.Fab") hide
      (effects (font (size 0.7 0.7) (thickness 0.15)) (justify left bottom))
    )
    (fp_text user "${REFERENCE}" (at -0.932 3.168 180) (layer "F.Fab") hide
      (effects (font (size 0.7 0.7) (thickness 0.15)) (justify left bottom))
    )
    (fp_rect (start -0.94 -0.47) (end 0.94 0.47) (layer "F.CrtYd") (width 0.05) (fill none))
    (fp_rect (start -0.499 -0.249) (end 0.499 0.249) (layer "F.Fab") (width 0.15) (fill none))
    (pad "1" smd roundrect (at -0.484 0 180) (size 0.59 0.64) (layers "F.Cu" "F.Paste" "F.Mask") (roundrect_rratio 0.25)
      (net 186 "/HDMI converter/LT9611_RST_N") (pintype "passive"))
    (pad "2" smd roundrect (at 0.484 0 180) (size 0.59 0.64) (layers "F.Cu" "F.Paste" "F.Mask") (roundrect_rratio 0.25)
      (net 1 "GND") (pintype "passive"))
  )
	(footprint "sa800u-baseboard-hw-footprints:R_0402_1005Metric" (layer "F.Cu")
    (tedit 5FD9C158)
    (at 134.388164 124.512952 180)
    (descr "Resistor SMD 0402")
    (tags "resistor SMD 0402")
    (property "Author" "Antmicro")
    (property "Current" "1A")
    (property "License" "Apache-2.0")
    (property "MPN" "ERJ2GE0R00X")
    (property "Manufacturer" "Panasonic")
    (property "Sheetfile" "hdmi-converter.kicad_sch")
    (property "Sheetname" "HDMI converter")
    (property "Tolerance" "")
    (property "Val" "0R")
    (attr smd)
    (fp_text reference "R16" (at 4.058164 -0.417048 180) (layer "F.SilkS")
      (effects (font (size 0.7 0.7) (thickness 0.15)) (justify left bottom))
    )
    (fp_text value "R_0R_0402" (at 0 1.4 180) (layer "F.Fab")
      (effects (font (size 0.7 0.7) (thickness 0.15)) (justify left bottom))
    )
    (fp_text user "Author: Antmicro" (at -0.95 4.169 180) (layer "F.Fab") hide
      (effects (font (size 0.7 0.7) (thickness 0.15)) (justify left bottom))
    )
    (fp_text user "License: Apache-2.0" (at -0.95 5.169 180) (layer "F.Fab") hide
      (effects (font (size 0.7 0.7) (thickness 0.15)) (justify left bottom))
    )
    (fp_text user "${REFERENCE}" (at -0.95 3.168 180) (layer "F.Fab") hide
      (effects (font (size 0.7 0.7) (thickness 0.15)) (justify left bottom))
    )
    (fp_rect (start -0.93 -0.47) (end 0.93 0.47) (layer "F.CrtYd") (width 0.05) (fill none))
    (fp_rect (start -0.5 -0.25) (end 0.5 0.25) (layer "F.Fab") (width 0.15) (fill none))
    (pad "1" smd roundrect (at -0.485 0 180) (size 0.59 0.64) (layers "F.Cu" "F.Paste" "F.Mask") (roundrect_rratio 0.25)
      (net 289 "/HDMI converter/I2C_ADDR") (pintype "passive"))
    (pad "2" smd roundrect (at 0.485 0 180) (size 0.59 0.64) (layers "F.Cu" "F.Paste" "F.Mask") (roundrect_rratio 0.25)
      (net 1 "GND") (pintype "passive"))
  )
	(footprint "sa800u-baseboard-hw-footprints:R_0402_1005Metric" (layer "F.Cu")
    (tedit 5FD9C158)
    (at 150.8 138)
    (descr "Resistor SMD 0402")
    (tags "resistor SMD 0402")
    (property "Author" "Antmicro")
    (property "License" "Apache-2.0")
    (property "MPN" "CR0402-FX-1002GLF")
    (property "Manufacturer" "Bourns")
    (property "Sheetfile" "som.kicad_sch")
    (property "Sheetname" "SoM")
    (property "Tolerance" "1%")
    (property "Val" "10k")
    (attr smd)
    (fp_text reference "R77" (at -1.19 1.3) (layer "F.SilkS")
      (effects (font (size 0.7 0.7) (thickness 0.15)) (justify left bottom))
    )
    (fp_text value "R_10k_0402" (at 0 1.4) (layer "F.Fab")
      (effects (font (size 0.7 0.7) (thickness 0.15)) (justify left bottom))
    )
    (fp_text user "Author: Antmicro" (at -0.95 4.169) (layer "F.Fab") hide
      (effects (font (size 0.7 0.7) (thickness 0.15)) (justify left bottom))
    )
    (fp_text user "License: Apache-2.0" (at -0.95 5.169) (layer "F.Fab") hide
      (effects (font (size 0.7 0.7) (thickness 0.15)) (justify left bottom))
    )
    (fp_text user "${REFERENCE}" (at -0.95 3.168) (layer "F.Fab") hide
      (effects (font (size 0.7 0.7) (thickness 0.15)) (justify left bottom))
    )
    (fp_rect (start -0.93 -0.47) (end 0.93 0.47) (layer "F.CrtYd") (width 0.05) (fill none))
    (fp_rect (start -0.5 -0.25) (end 0.5 0.25) (layer "F.Fab") (width 0.15) (fill none))
    (pad "1" smd roundrect (at -0.485 0) (size 0.59 0.64) (layers "F.Cu" "F.Paste" "F.Mask") (roundrect_rratio 0.25)
      (net 385 "Net-(Q5-Pad3)") (pintype "passive"))
    (pad "2" smd roundrect (at 0.485 0) (size 0.59 0.64) (layers "F.Cu" "F.Paste" "F.Mask") (roundrect_rratio 0.25)
      (net 371 "Net-(D14-Pad2)") (pintype "passive"))
  )
)
